FILE_TYPE = MULTI_PHYS_TABLE;

PART 'DIODE_TVS'

{========================================================================================}
:VALUE             | PART_TYPE | MATERIAL | PART_NUMBER    = STANDARD    | LIFECYCLE     | PART_NUMBER   | JEDEC_TYPE             | DESCRIPTION                               | MANUFTR | MANUF_PN          | RD_CMPLS_LVL | CMPLS_LVL | CLASS | DIP_SMD | FP_ECN             | FROM_PJ       | DATA                      | EE_CHECK_LIST | STATUS | PSL | PREFERENCE | CREATOR | CREATEDAY  ;
{========================================================================================}
 'SMF13A'          | 'SMLF'    | 'IC'     | 'BC00013AZ00'(!) = ''          | ''            | 'BC00013AZ00' | 'SOD123F'              | 'DIODE SMD SMF13A(13V,9.3A)SOD-123F'      | 'LFI'   | 'SMF13A'          | 'EP(V1)'     | ''        | 'IC'  | ''      | ''                 | 'JBE-CH'      | 'LFI_SMF13A.pdf'          | ''            | ''     | ''  | ''         | ''      | '20160223'
 'SMF13A'          | 'SMLF'    | 'EMPTY'  | 'BC00013AZ00'(!) = ''          | ''            | 'BC00013AZ00' | 'SOD123F'              | 'DIODE SMD SMF13A(13V,9.3A)SOD-123F'      | 'LFI'   | 'SMF13A'          | 'EP(V1)'     | ''        | 'IC'  | ''      | ''                 | 'JBE-CH'      | 'LFI_SMF13A.pdf'          | ''            | ''     | ''  | ''         | ''      | '20160223'
 'SMF13A'          | 'SMLF'    | 'IC'     | 'BCSMF13AZ01'(!) = ''          | ''            | 'BCSMF13AZ01' | 'SOD123FL_2-8X1-8'     | 'DIODE SMD SMF13A(13V,9.3A)SOD-123FL'     | 'PJT'   | 'SMF13A'          | 'EP(V1)'     | ''        | 'IC'  | ''      | ''                 | 'JBE-CH'      | 'PJT_SMF13A.pdf'          | ''            | ''     | ''  | ''         | ''      | '20160223'
 'SMF13A'          | 'SMLF'    | 'EMPTY'  | 'BCSMF13AZ01'(!) = ''          | ''            | 'BCSMF13AZ01' | 'SOD123FL_2-8X1-8'     | 'DIODE SMD SMF13A(13V,9.3A)SOD-123FL'     | 'PJT'   | 'SMF13A'          | 'EP(V1)'     | ''        | 'IC'  | ''      | ''                 | 'JBE-CH'      | 'PJT_SMF13A.pdf'          | ''            | ''     | ''  | ''         | ''      | '20160223'
 'P4HE13A'         | 'SMLF'    | 'IC'     | 'BC4HE13AZ00'(!) = ''          | ''            | 'BC4HE13AZ00' | 'SOD123HE_2-8X1-8'     | 'DIODE SMD P4HE13A(13V,18.6A,400W)'       | 'PJT'   | 'P4HE13A'         | 'EP(V1)'     | ''        | 'IC'  | ''      | ''                 | 'JBE-CHARLES' | 'PJT_P4HE13A.pdf'         | ''            | ''     | ''  | ''         | ''      | '20160324'
 'P4HE13A'         | 'SMLF'    | 'EMPTY'  | 'BC4HE13AZ00'(!) = ''          | ''            | 'BC4HE13AZ00' | 'SOD123HE_2-8X1-8'     | 'DIODE SMD P4HE13A(13V,18.6A,400W)'       | 'PJT'   | 'P4HE13A'         | 'EP(V1)'     | ''        | 'IC'  | ''      | ''                 | 'JBE-CHARLES' | 'PJT_P4HE13A.pdf'         | ''            | ''     | ''  | ''         | ''      | '20160324'
 'SMDJ60A'         | 'SMLF'    | 'IC'     | 'BCSMDJ60Z00'(!) = ''          | ''            | 'BCSMDJ60Z00' | 'D_SMDJ60A'            | 'DIODE SMD SMDJ60A(60V,3000W)DO-214AB'    | 'LFI'   | 'SMDJ60A'         | 'EP(V1)'     | 'EP(V1)'  | 'IC'  | ''      | ''                 | 'T2M-JACK'    | 'LFI_SMDJ60A.pdf'         | ''            | ''     | ''  | ''         | ''      | '20170803'
 'SMDJ60A'         | 'SMLF'    | 'EMPTY'  | 'BCSMDJ60Z00'(!) = ''          | ''            | 'BCSMDJ60Z00' | 'D_SMDJ60A'            | 'DIODE SMD SMDJ60A(60V,3000W)DO-214AB'    | 'LFI'   | 'SMDJ60A'         | 'EP(V1)'     | 'EP(V1)'  | 'IC'  | ''      | ''                 | 'T2M-JACK'    | 'LFI_SMDJ60A.pdf'         | ''            | ''     | ''  | ''         | ''      | '20170803'
 'SMF14A'          | 'SMLF'    | 'IC'     | 'BCSMF14AZ01'(!) = ''          | ''            | 'BCSMF14AZ01' | 'SOD123F'              | 'DIODE SMF14A(14V,8.6A)SOD-123FL'         | 'LFI'   | 'SMF14A'          | 'EP(V1)'     | 'EP(V1)'  | 'IC'  | ''      | ''                 | 'F0G-EGBERT'  | 'LFI_SMF14A.pdf'          | ''            | ''     | ''  | ''         | ''      | '20190805'
 'SMF14A'          | 'SMLF'    | 'EMPTY'  | 'BCSMF14AZ01'(!) = ''          | ''            | 'BCSMF14AZ01' | 'SOD123F'              | 'DIODE SMF14A(14V,8.6A)SOD-123FL'         | 'LFI'   | 'SMF14A'          | 'EP(V1)'     | 'EP(V1)'  | 'IC'  | ''      | ''                 | 'F0G-EGBERT'  | 'LFI_SMF14A.pdf'          | ''            | ''     | ''  | ''         | ''      | '20190805'
 'DFLT14A-7'       | 'SMLF'    | 'IC'     | 'BCFLT14AZ00'(!) = ''          | ''            | 'BCFLT14AZ00' | 'POWERDI123_ACXA'      | 'DIODE TVS DFLT14A-7(14V,9.7A,225W)'      | 'DDS'   | 'DFLT14A-7'       | 'EP(V1)'     | ''        | 'IC'  | ''      | ''                 | 'F0G-EGBERT'  | 'DDS_DFLT14A-7.pdf'       | ''            | ''     | ''  | ''         | ''      | '20190924'
 'DFLT14A-7'       | 'SMLF'    | 'EMPTY'  | 'BCFLT14AZ00'(!) = ''          | ''            | 'BCFLT14AZ00' | 'POWERDI123_ACXA'      | 'DIODE TVS DFLT14A-7(14V,9.7A,225W)'      | 'DDS'   | 'DFLT14A-7'       | 'EP(V1)'     | ''        | 'IC'  | ''      | ''                 | 'F0G-EGBERT'  | 'DDS_DFLT14A-7.pdf'       | ''            | ''     | ''  | ''         | ''      | '20190924'
 'SMAJ14A'         | 'SMLF'    | 'IC'     | 'BCMAJ14AZ02'(!) = ''          | ''            | 'BCMAJ14AZ02' | 'D1710_SMAXA'          | 'DIODE TVS SMAJ14A(14V,17.2A,400W)'       | 'LFI'   | 'SMAJ14A'         | 'EP(V1)'     | ''        | 'IC'  | ''      | ''                 | 'F0G-EGBERT'  | 'LFI_SMAJ14A.pdf'         | ''            | ''     | ''  | ''         | ''      | '20190925'
 'SMAJ14A'         | 'SMLF'    | 'EMPTY'  | 'BCMAJ14AZ02'(!) = ''          | ''            | 'BCMAJ14AZ02' | 'D1710_SMAXA'          | 'DIODE TVS SMAJ14A(14V,17.2A,400W)'       | 'LFI'   | 'SMAJ14A'         | 'EP(V1)'     | ''        | 'IC'  | ''      | ''                 | 'F0G-EGBERT'  | 'LFI_SMAJ14A.pdf'         | ''            | ''     | ''  | ''         | ''      | '20190925'
 'SMF14A'          | 'SMLF'    | 'IC'     | 'BCSMF14AZ02'(!) = ''          | ''            | 'BCSMF14AZ02' | 'SOD123FL_2-8X1-8'     | 'DIODE TVS SMF14A(14V,20A,200W)'          | 'PJT'   | 'SMF14A'          | 'EP(V1)'     | ''        | 'IC'  | ''      | ''                 | 'F0G-EGBERT'  | 'PJT_SMF14A.pdf'          | ''            | ''     | ''  | ''         | ''      | '20200210'
 'SMF14A'          | 'SMLF'    | 'EMPTY'  | 'BCSMF14AZ02'(!) = ''          | ''            | 'BCSMF14AZ02' | 'SOD123FL_2-8X1-8'     | 'DIODE TVS SMF14A(14V,20A,200W)'          | 'PJT'   | 'SMF14A'          | 'EP(V1)'     | ''        | 'IC'  | ''      | ''                 | 'F0G-EGBERT'  | 'PJT_SMF14A.pdf'          | ''            | ''     | ''  | ''         | ''      | '20200210'
 '5.0SMDJ58A'      | 'SMLF'    | 'IC'     | 'BCMDJ58AZ01'(!) = ''          | ''            | 'BCMDJ58AZ01' | 'D_SMDJ60A'            | 'DIODE TVS 5.0SMDJ58A(58V,53.5A,5000W)'   | 'LFI'   | '5.0SMDJ58A'      | 'EP(V1)'     | ''        | 'IC'  | ''      | ''                 | 'S8A-YC'      | 'LFI_5.0SMDJ58A.pdf'      | ''            | ''     | ''  | ''         | ''      | '20200406'
 '5.0SMDJ58A'      | 'SMLF'    | 'EMPTY'  | 'BCMDJ58AZ01'(!) = ''          | ''            | 'BCMDJ58AZ01' | 'D_SMDJ60A'            | 'DIODE TVS 5.0SMDJ58A(58V,53.5A,5000W)'   | 'LFI'   | '5.0SMDJ58A'      | 'EP(V1)'     | ''        | 'IC'  | ''      | ''                 | 'S8A-YC'      | 'LFI_5.0SMDJ58A.pdf'      | ''            | ''     | ''  | ''         | ''      | '20200406'
 'SMAJ5.0A-13-F'   | 'SMLF'    | 'IC'     | 'BCMAJ50AZ00'(!) = ''          | ''            | 'BCMAJ50AZ00' | 'D2010XF'              | 'DIODE SMD SMAJ5.0A-13-F(5V,400W)SMA'     | 'DDS'   | 'SMAJ5.0A-13-F'   | 'EP(V1)'     | 'EP(V1)'  | 'IC'  | ''      | ''                 | 'IOX-EGBERT'  | 'DDS_SMAJ5.0A-13-F.pdf'   | ''            | ''     | ''  | ''         | ''      | '20200610'
 'SMAJ5.0A-13-F'   | 'SMLF'    | 'EMPTY'  | 'BCMAJ50AZ00'(!) = ''          | ''            | 'BCMAJ50AZ00' | 'D2010XF'              | 'DIODE SMD SMAJ5.0A-13-F(5V,400W)SMA'     | 'DDS'   | 'SMAJ5.0A-13-F'   | 'EP(V1)'     | 'EP(V1)'  | 'IC'  | ''      | ''                 | 'IOX-EGBERT'  | 'DDS_SMAJ5.0A-13-F.pdf'   | ''            | ''     | ''  | ''         | ''      | '20200610'
 'SMBJ14A-13-F'    | 'SMLF'    | 'IC'     | 'BCMBJ14AZ01'(!) = ''          | ''            | 'BCMBJ14AZ01' | 'D_SMBJ14AXA'          | 'DIODE TVS SMBJ14A-13-F(14V,25.8A,600W)'  | 'DDS'   | 'SMBJ14A-13-F'    | 'EP(V1)'     | ''        | 'IC'  | ''      | ''                 | 'IOX-EGBERT'  | 'DDS_SMBJ14A-13-F.pdf'    | ''            | ''     | ''  | ''         | ''      | '20200612'
 'SMBJ14A-13-F'    | 'SMLF'    | 'EMPTY'  | 'BCMBJ14AZ01'(!) = ''          | ''            | 'BCMBJ14AZ01' | 'D_SMBJ14AXA'          | 'DIODE TVS SMBJ14A-13-F(14V,25.8A,600W)'  | 'DDS'   | 'SMBJ14A-13-F'    | 'EP(V1)'     | ''        | 'IC'  | ''      | ''                 | 'IOX-EGBERT'  | 'DDS_SMBJ14A-13-F.pdf'    | ''            | ''     | ''  | ''         | ''      | '20200612'
 'SMBJ14A'         | 'SMLF'    | 'IC'     | 'BCMBJ14AZ00'(!) = ''          | ''            | 'BCMBJ14AZ00' | 'D_SMBJ14A'            | 'DIODE TVS SMBJ14A(14V,25.9A,600W)'       | 'LFI'   | 'SMBJ14A'         | 'EP(V1)'     | ''        | 'IC'  | ''      | ''                 | 'IOX-EGBERT'  | 'LFI_SMBJ14A.pdf'         | ''            | ''     | ''  | ''         | ''      | '20200616'
 'SMBJ14A'         | 'SMLF'    | 'EMPTY'  | 'BCMBJ14AZ00'(!) = ''          | ''            | 'BCMBJ14AZ00' | 'D_SMBJ14A'            | 'DIODE TVS SMBJ14A(14V,25.9A,600W)'       | 'LFI'   | 'SMBJ14A'         | 'EP(V1)'     | ''        | 'IC'  | ''      | ''                 | 'IOX-EGBERT'  | 'LFI_SMBJ14A.pdf'         | ''            | ''     | ''  | ''         | ''      | '20200616'
 'SMAJ5.0A'        | 'SMLF'    | 'IC'     | 'BCMAJ50AZ01'(!) = ''          | ''            | 'BCMAJ50AZ01' | 'D1710_SMAXA'          | 'DIODE TVS SMAJ5.0A(5V,43.5A,400W)'       | 'LFI'   | 'SMAJ5.0A'        | 'EP(V1)'     | ''        | 'IC'  | ''      | ''                 | 'F0CE-JAY'    | 'LFI_SMAJ5.0A.pdf'        | ''            | ''     | ''  | ''         | ''      | '20200620'
 'SMAJ5.0A'        | 'SMLF'    | 'EMPTY'  | 'BCMAJ50AZ01'(!) = ''          | ''            | 'BCMAJ50AZ01' | 'D1710_SMAXA'          | 'DIODE TVS SMAJ5.0A(5V,43.5A,400W)'       | 'LFI'   | 'SMAJ5.0A'        | 'EP(V1)'     | ''        | 'IC'  | ''      | ''                 | 'F0CE-JAY'    | 'LFI_SMAJ5.0A.pdf'        | ''            | ''     | ''  | ''         | ''      | '20200620'
 'P4SMAJ5.0A'      | 'SMLF'    | 'IC'     | 'BCMAJ50AZ02'(!) = ''          | ''            | 'BCMAJ50AZ02' | 'D2010XH'              | 'DIODE TVS P4SMAJ5.0A(5V,43.5A,400W)'     | 'PJT'   | 'P4SMAJ5.0A'      | 'EP(V1)'     | ''        | 'IC'  | ''      | ''                 | 'F0CE-JAY'    | 'PJT_P4SMAJ5.0A.pdf'      | ''            | ''     | ''  | ''         | ''      | '20200620'
 'P4SMAJ5.0A'      | 'SMLF'    | 'EMPTY'  | 'BCMAJ50AZ02'(!) = ''          | ''            | 'BCMAJ50AZ02' | 'D2010XH'              | 'DIODE TVS P4SMAJ5.0A(5V,43.5A,400W)'     | 'PJT'   | 'P4SMAJ5.0A'      | 'EP(V1)'     | ''        | 'IC'  | ''      | ''                 | 'F0CE-JAY'    | 'PJT_P4SMAJ5.0A.pdf'      | ''            | ''     | ''  | ''         | ''      | '20200620'
 'SMC5K14A-M3/I'   | 'SMLF'    | 'IC'     | 'BCC5K14AZ01'(!) = ''          | ''            | 'BCC5K14AZ01' | 'D2723_SMCXK'          | 'DIODE SMD SMC5K14A-M3/I(14V,216A)'       | 'SIL'   | 'SMC5K14A-M3/I'   | 'EP(V1)'     | ''        | 'IC'  | ''      | ''                 | 'F0CE-EGBERT' | 'SIL_SMC5K14A-M3I.pdf'    | ''            | ''     | ''  | ''         | ''      | '20200904'
 'SMC5K14A-M3/I'   | 'SMLF'    | 'EMPTY'  | 'BCC5K14AZ01'(!) = ''          | ''            | 'BCC5K14AZ01' | 'D2723_SMCXK'          | 'DIODE SMD SMC5K14A-M3/I(14V,216A)'       | 'SIL'   | 'SMC5K14A-M3/I'   | 'EP(V1)'     | ''        | 'IC'  | ''      | ''                 | 'F0CE-EGBERT' | 'SIL_SMC5K14A-M3I.pdf'    | ''            | ''     | ''  | ''         | ''      | '20200904'
 'P4SMAJ13AS'      | 'SMLF'    | 'IC'     | 'BCAJ13ASZ00'(!) = ''          | ''            | 'BCAJ13ASZ00' | 'D2010XH'              | 'DIODE SMD P4SMAJ13AS(13V,18.6A)'         | 'PJT'   | 'P4SMAJ13AS'      | 'EP(V1)'     | ''        | 'IC'  | ''      | ''                 | 'S3IS-MARK'   | 'PJT_P4SMAJ13AS.pdf'      | ''            | ''     | ''  | ''         | ''      | '20200908'
 'P4SMAJ13AS'      | 'SMLF'    | 'EMPTY'  | 'BCAJ13ASZ00'(!) = ''          | ''            | 'BCAJ13ASZ00' | 'D2010XH'              | 'DIODE SMD P4SMAJ13AS(13V,18.6A)'         | 'PJT'   | 'P4SMAJ13AS'      | 'EP(V1)'     | ''        | 'IC'  | ''      | ''                 | 'S3IS-MARK'   | 'PJT_P4SMAJ13AS.pdf'      | ''            | ''     | ''  | ''         | ''      | '20200908'
 'SMBJ58A'         | 'SMLF'    | 'IC'     | 'BC0MBJ58Z00'(!) = ''          | ''            | 'BC0MBJ58Z00' | 'D_SMBJ14A'            | 'DIODE SMD SMBJ58A(58V,6.5A)'             | 'LFI'   | 'SMBJ58A'         | 'EP(V1)'     | 'EP(V1)'  | 'IC'  | ''      | ''                 | 'P0A-STEVE'   | 'LFI_SMBJ58A.pdf'         | ''            | ''     | ''  | ''         | ''      | '20210304'
 'SMBJ58A'         | 'SMLF'    | 'EMPTY'  | 'BC0MBJ58Z00'(!) = ''          | ''            | 'BC0MBJ58Z00' | 'D_SMBJ14A'            | 'DIODE SMD SMBJ58A(58V,6.5A)'             | 'LFI'   | 'SMBJ58A'         | 'EP(V1)'     | 'EP(V1)'  | 'IC'  | ''      | ''                 | 'P0A-STEVE'   | 'LFI_SMBJ58A.pdf'         | ''            | ''     | ''  | ''         | ''      | '20210304'
 'SMDJ54A'         | 'SMLF'    | 'IC'     | 'BCMDJ54AZ00'(!) = ''          | ''            | 'BCMDJ54AZ00' | 'D_SMDJ60A'            | 'DIODE SMD SMDJ54A(54V,3000W)'            | 'LFI'   | 'SMDJ54A'         | 'EP(V1)'     | ''        | 'IC'  | ''      | ''                 | 'S7P-VINCENT' | 'LFI_SMDJ54A.pdf'         | ''            | ''     | ''  | ''         | ''      | '20210325'
 'SMDJ54A'         | 'SMLF'    | 'EMPTY'  | 'BCMDJ54AZ00'(!) = ''          | ''            | 'BCMDJ54AZ00' | 'D_SMDJ60A'            | 'DIODE SMD SMDJ54A(54V,3000W)'            | 'LFI'   | 'SMDJ54A'         | 'EP(V1)'     | ''        | 'IC'  | ''      | ''                 | 'S7P-VINCENT' | 'LFI_SMDJ54A.pdf'         | ''            | ''     | ''  | ''         | ''      | '20210325'
 '5.0SMDJ54A'      | 'SMLF'    | 'IC'     | 'BCMDJ54AZ01'(!) = ''          | ''            | 'BCMDJ54AZ01' | 'D_SMDJ60A'            | 'DIODE TVS 5.0SMDJ54A(54V,57.5A,5000W)'   | 'LFI'   | '5.0SMDJ54A'      | 'EP(V1)'     | ''        | 'IC'  | ''      | ''                 | 'S7P-VINCENT' | 'LFI_5.0SMDJ54A.pdf'      | ''            | ''     | ''  | ''         | ''      | '20210429'
 '5.0SMDJ54A'      | 'SMLF'    | 'EMPTY'  | 'BCMDJ54AZ01'(!) = ''          | ''            | 'BCMDJ54AZ01' | 'D_SMDJ60A'            | 'DIODE TVS 5.0SMDJ54A(54V,57.5A,5000W)'   | 'LFI'   | '5.0SMDJ54A'      | 'EP(V1)'     | ''        | 'IC'  | ''      | ''                 | 'S7P-VINCENT' | 'LFI_5.0SMDJ54A.pdf'      | ''            | ''     | ''  | ''         | ''      | '20210429'
 'AZ5413-01F.R7GR' | 'SMLF'    | 'IC'     | 'BC41301FZ00'(!) = ''          | ''            | 'BC41301FZ00' | 'D0402_AZ5413-01FR7GR' | 'DIODE ESD AZ5413-01F.R7GR(3.3V,1UA,DFN)' | 'AMZ'   | 'AZ5413-01F.R7GR' | 'EP(V1)'     | 'EP(V1)'  | 'IC'  | ''      | ''                 | '2RE-JOHN'    | 'AMZ_AZ5413-01F.R7GR.pdf' | ''            | ''     | ''  | ''         | ''      | '20210511'
 'AZ5413-01F.R7GR' | 'SMLF'    | 'EMPTY'  | 'BC41301FZ00'(!) = ''          | ''            | 'BC41301FZ00' | 'D0402_AZ5413-01FR7GR' | 'DIODE ESD AZ5413-01F.R7GR(3.3V,1UA,DFN)' | 'AMZ'   | 'AZ5413-01F.R7GR' | 'EP(V1)'     | 'EP(V1)'  | 'IC'  | ''      | ''                 | '2RE-JOHN'    | 'AMZ_AZ5413-01F.R7GR.pdf' | ''            | ''     | ''  | ''         | ''      | '20210511'
 '8.0SMDJ48A'      | 'SMLF'    | 'IC'     | 'BCMDJ48AZ00'(!) = ''          | ''            | 'BCMDJ48AZ00' | 'D_SMDJ60A'            | 'DIODE SMD 8.0SMDJ48A(48V)'               | 'LFI'   | '8.0SMDJ48A'      | 'EP(V1)'     | ''        | 'IC'  | ''      | ''                 | 'S1L-BERNIE'  | 'LFI_8.0SMDJ48A.pdf'      | ''            | ''     | ''  | ''         | ''      | '20210513'
 '8.0SMDJ48A'      | 'SMLF'    | 'EMPTY'  | 'BCMDJ48AZ00'(!) = ''          | ''            | 'BCMDJ48AZ00' | 'D_SMDJ60A'            | 'DIODE SMD 8.0SMDJ48A(48V)'               | 'LFI'   | '8.0SMDJ48A'      | 'EP(V1)'     | ''        | 'IC'  | ''      | ''                 | 'S1L-BERNIE'  | 'LFI_8.0SMDJ48A.pdf'      | ''            | ''     | ''  | ''         | ''      | '20210513'
 'SMAJ13A'         | 'SMLF'    | 'IC'     | 'BCMAJ13AZ04'(!) = ''          | ''            | 'BCMAJ13AZ04' | 'D1710_SMAXA'          | 'DIODE TVS SMAJ13A(14V,17.2A,400W)'       | 'LFI'   | 'SMAJ13A'         | 'EP(V1)'     | ''        | 'IC'  | ''      | ''                 | 'F0CE-SAM'    | 'LFI_SMAJ13A.pdf'         | ''            | ''     | ''  | ''         | ''      | '20210705'
 'SMAJ13A'         | 'SMLF'    | 'EMPTY'  | 'BCMAJ13AZ04'(!) = ''          | ''            | 'BCMAJ13AZ04' | 'D1710_SMAXA'          | 'DIODE TVS SMAJ13A(14V,17.2A,400W)'       | 'LFI'   | 'SMAJ13A'         | 'EP(V1)'     | ''        | 'IC'  | ''      | ''                 | 'F0CE-SAM'    | 'LFI_SMAJ13A.pdf'         | ''            | ''     | ''  | ''         | ''      | '20210705'
 'SMC5K13A-M3/I'   | 'SMLF'    | 'IC'     | 'BCC5K13AZ00'(!) = ''          | ''            | 'BCC5K13AZ00' | 'D2723_SMCXK'          | 'DIODE TVS SMC5K13A-M3/I(13V,216A)AEC'    | 'SIL'   | 'SMC5K13A-M3/I'   | 'EP(V1)'     | ''        | 'IC'  | ''      | 'SMC5K13A-M3I.msg' | 'F0CE-SAM'    | 'SIL_SMC5K13A-M3I.pdf'    | ''            | ''     | ''  | ''         | ''      | '20210705'
 'SMC5K13A-M3/I'   | 'SMLF'    | 'EMPTY'  | 'BCC5K13AZ00'(!) = ''          | ''            | 'BCC5K13AZ00' | 'D2723_SMCXK'          | 'DIODE TVS SMC5K13A-M3/I(13V,216A)AEC'    | 'SIL'   | 'SMC5K13A-M3/I'   | 'EP(V1)'     | ''        | 'IC'  | ''      | 'SMC5K13A-M3I.msg' | 'F0CE-SAM'    | 'SIL_SMC5K13A-M3I.pdf'    | ''            | ''     | ''  | ''         | ''      | '20210705'
 'SMBJ14A-M3/52'   | 'SMLF'    | 'IC'     | 'BCMBJ14AZ03'(!) = ''          | ''            | 'BCMBJ14AZ03' | 'D_SMBJ14AXB'          | 'DIODE SMBJ14A-M3/52(14V,25.9A)'          | 'SIL'   | 'SMBJ14A-M3/52'   | 'EP(V1)'     | ''        | 'IC'  | ''      | ''                 | 'F0CE-FRANK'  | 'SIL_SMBJ14A-M352.pdf'    | ''            | ''     | ''  | ''         | ''      | '20211026'
 'SMBJ14A-M3/52'   | 'SMLF'    | 'EMPTY'  | 'BCMBJ14AZ03'(!) = ''          | ''            | 'BCMBJ14AZ03' | 'D_SMBJ14AXB'          | 'DIODE SMBJ14A-M3/52(14V,25.9A)'          | 'SIL'   | 'SMBJ14A-M3/52'   | 'EP(V1)'     | ''        | 'IC'  | ''      | ''                 | 'F0CE-FRANK'  | 'SIL_SMBJ14A-M352.pdf'    | ''            | ''     | ''  | ''         | ''      | '20211026'
 '5KMC14AS'        | 'SMLF'    | 'IC'     | 'BCMC14ASZ00'(!) = ''          | ''            | 'BCMC14ASZ00' | 'D2723_SMCXG'          | 'DIODE SMD 5KMC14AS (5000W,14V)'          | 'PJT'   | '5KMC14AS'        | 'EP(V1)'     | ''        | 'IC'  | ''      | ''                 | 'F0T-PETER'   | 'PJT_5KMC14AS.pdf'        | ''            | ''     | ''  | ''         | ''      | '20221207'
 '5KMC14AS'        | 'SMLF'    | 'EMPTY'  | 'BCMC14ASZ00'(!) = ''          | ''            | 'BCMC14ASZ00' | 'D2723_SMCXG'          | 'DIODE SMD 5KMC14AS (5000W,14V)'          | 'PJT'   | '5KMC14AS'        | 'EP(V1)'     | ''        | 'IC'  | ''      | ''                 | 'F0T-PETER'   | 'PJT_5KMC14AS.pdf'        | ''            | ''     | ''  | ''         | ''      | '20221207'
 'SMF4L14A-7'      | 'SMLF'    | 'IC'     | 'BC04L14AZ00'(!) = 'Potential' | 'P/N Release' | 'BC04L14AZ00' | 'DO-219AA_SMF'         | 'DIODE SMD SMF4L14A-7 (14V, 400W)'        | 'DDS'   | 'SMF4L14A-7'      | 'EP(V1)'     | ''        | 'IC'  | ''      | ''                 | 'S8G-MICHAEL' | 'DDS_SMF4L14A-7.pdf'      | ''            | ''     | ''  | ''         | ''      | '20230323'
 'SMF4L14A-7'      | 'SMLF'    | 'EMPTY'  | 'BC04L14AZ00'(!) = 'Potential' | 'P/N Release' | 'BC04L14AZ00' | 'DO-219AA_SMF'         | 'DIODE SMD SMF4L14A-7 (14V, 400W)'        | 'DDS'   | 'SMF4L14A-7'      | 'EP(V1)'     | ''        | 'IC'  | ''      | ''                 | 'S8G-MICHAEL' | 'DDS_SMF4L14A-7.pdf'      | ''            | ''     | ''  | ''         | ''      | '20230323'

END_PART

END.

